(kicad_pcb
	(version 20260206)
	(generator "pcbnew")
	(generator_version "10.0")
	(general
		(thickness 1.6)
		(legacy_teardrops no)
	)
	(paper "A4")
	(title_block
		(title "01162023_DA0F0TEBIF0_F0T_Expander_BD_F_brd_V02_OCP.brd")
		(comment 1 "Grand Teton / footprint 1840 of 9728 (U6), pads 1-110 of 484")
	)
	(layers
		(0 "F.Cu" signal "TOP")
		(4 "In1.Cu" signal "GND")
		(6 "In2.Cu" signal "VCC")
		(8 "In3.Cu" signal "VCC1")
		(10 "In4.Cu" signal "GND1")
		(12 "In5.Cu" signal "IN1")
		(14 "In6.Cu" signal "GND2")
		(16 "In7.Cu" signal "IN2")
		(18 "In8.Cu" signal "GND3")
		(20 "In9.Cu" signal "IN3")
		(22 "In10.Cu" signal "GND4")
		(24 "In11.Cu" signal "IN4")
		(26 "In12.Cu" signal "GND5")
		(28 "In13.Cu" signal "IN5")
		(30 "In14.Cu" signal "GND6")
		(32 "In15.Cu" signal "IN6")
		(34 "In16.Cu" signal "GND7")
		(2 "B.Cu" signal "BOTTOM")
		(9 "F.Adhes" user "F.Adhesive")
		(11 "B.Adhes" user "B.Adhesive")
		(13 "F.Paste" user "Package Geometry/Pastemask Top")
		(15 "B.Paste" user "Package Geometry/Pastemask Bottom")
		(5 "F.SilkS" user "Ref Des/Silkscreen Top")
		(7 "B.SilkS" user "Ref Des/Silkscreen Bottom")
		(1 "F.Mask" user "Board Geometry/Soldermask Top")
		(3 "B.Mask" user "Board Geometry/Soldermask Bottom")
		(17 "Dwgs.User" user "User.Drawings")
		(19 "Cmts.User" user "User.Comments")
		(21 "Eco1.User" user "User.Eco1")
		(23 "Eco2.User" user "User.Eco2")
		(25 "Edge.Cuts" user "Board Geometry/Outline")
		(27 "Margin" user)
		(31 "F.CrtYd" user "Package Geometry/Place Bound Top")
		(29 "B.CrtYd" user "Package Geometry/Place Bound Bottom")
		(35 "F.Fab" user "Ref Des/Assembly Top")
		(33 "B.Fab" user "Ref Des/Assembly Bottom")
	)
	(footprint ""
		(layer "F.Cu")
		(at 342.493854 -219.587064)
		(property "Reference" "U6"
			(at -10.3632 -10.963148 0)
			(unlocked yes)
			(layer "F.SilkS")
			(effects
				(font
					(size 0.7874 0.5842)
					(thickness 0.1524)
				)
				(justify left)
			)
		)
		(property "Value" ""
			(at 0 0 0)
			(layer "F.Fab")
			(effects
				(font
					(size 1.27 1.27)
				)
			)
		)
		(duplicate_pad_numbers_are_jumpers no)
		(pad "A1" smd circle
			(at -8.400034 -8.400034)
			(size 0.4064 0.4064)
			(layers "F.Cu" "F.Mask" "F.Paste")
			(net "GND")
		)
		(pad "A2" smd circle
			(at -7.599934 -8.400034)
			(size 0.4064 0.4064)
			(layers "F.Cu" "F.Mask" "F.Paste")
			(net "RST_MB_PERST_1_ISO_R_N")
		)
		(pad "A3" smd circle
			(at -6.800088 -8.400034)
			(size 0.4064 0.4064)
			(layers "F.Cu" "F.Mask" "F.Paste")
			(net "RST_GPU_PERST_0_N")
		)
		(pad "A4" smd circle
			(at -5.999988 -8.400034)
			(size 0.4064 0.4064)
			(layers "F.Cu" "F.Mask" "F.Paste")
			(net "PRSNT_SSD2_R_N")
		)
		(pad "A5" smd circle
			(at -5.199888 -8.400034)
			(size 0.4064 0.4064)
			(layers "F.Cu" "F.Mask" "F.Paste")
			(net "SSD2_PWRDIS")
		)
		(pad "A6" smd circle
			(at -4.400042 -8.400034)
			(size 0.4064 0.4064)
			(layers "F.Cu" "F.Mask" "F.Paste")
			(net "JP_FPGA_DEBUG_N")
		)
		(pad "A7" smd circle
			(at -3.599942 -8.400034)
			(size 0.4064 0.4064)
			(layers "F.Cu" "F.Mask" "F.Paste")
			(net "FM_SOL_UART_CH_SEL_R")
		)
		(pad "A8" smd circle
			(at -2.800096 -8.400034)
			(size 0.4064 0.4064)
			(layers "F.Cu" "F.Mask" "F.Paste")
			(net "SMB_PEX2_FPGA_SDA")
		)
		(pad "A9" smd circle
			(at -1.999996 -8.400034)
			(size 0.4064 0.4064)
			(layers "F.Cu" "F.Mask" "F.Paste")
			(net "PWRGD_P12V_SSD0_R")
		)
		(pad "A10" smd circle
			(at -1.199896 -8.400034)
			(size 0.4064 0.4064)
			(layers "F.Cu" "F.Mask" "F.Paste")
			(net "PRSNT_SSD1_R_N")
		)
		(pad "A11" smd circle
			(at -0.40005 -8.400034)
			(size 0.4064 0.4064)
			(layers "F.Cu" "F.Mask" "F.Paste")
			(net "SSD1_PWRDIS")
		)
		(pad "A12" smd circle
			(at 0.40005 -8.400034)
			(size 0.4064 0.4064)
			(layers "F.Cu" "F.Mask" "F.Paste")
			(net "SMB_BIC_FPGA_R_SDA")
		)
		(pad "A13" smd circle
			(at 1.199896 -8.400034)
			(size 0.4064 0.4064)
			(layers "F.Cu" "F.Mask" "F.Paste")
			(net "PWRGD_P12V_SSD3_R")
		)
		(pad "A14" smd circle
			(at 1.999996 -8.400034)
			(size 0.4064 0.4064)
			(layers "F.Cu" "F.Mask" "F.Paste")
			(net "RST_SSD3_PERST_N")
		)
		(pad "A15" smd circle
			(at 2.800096 -8.400034)
			(size 0.4064 0.4064)
			(layers "F.Cu" "F.Mask" "F.Paste")
			(net "SSD4_PWRDIS")
		)
		(pad "A16" smd circle
			(at 3.599942 -8.400034)
			(size 0.4064 0.4064)
			(layers "F.Cu" "F.Mask" "F.Paste")
			(net "PWRGD_P12V_SSD5_R")
		)
		(pad "A17" smd circle
			(at 4.400042 -8.400034)
			(size 0.4064 0.4064)
			(layers "F.Cu" "F.Mask" "F.Paste")
			(net "RST_SSD5_PERST_N")
		)
		(pad "A18" smd circle
			(at 5.199888 -8.400034)
			(size 0.4064 0.4064)
			(layers "F.Cu" "F.Mask" "F.Paste")
			(net "PWRGD_P3V3_SSD6_R")
		)
		(pad "A19" smd circle
			(at 5.999988 -8.400034)
			(size 0.4064 0.4064)
			(layers "F.Cu" "F.Mask" "F.Paste")
			(net "SSD6_CLK_EN_N")
		)
		(pad "A20" smd circle
			(at 6.800088 -8.400034)
			(size 0.4064 0.4064)
			(layers "F.Cu" "F.Mask" "F.Paste")
			(net "SSD7_PWR_EN")
		)
		(pad "A21" smd circle
			(at 7.599934 -8.400034)
			(size 0.4064 0.4064)
			(layers "F.Cu" "F.Mask" "F.Paste")
			(net "BIC_FORCE_THROTTLE_R_N")
		)
		(pad "A22" smd circle
			(at 8.400034 -8.400034)
			(size 0.4064 0.4064)
			(layers "F.Cu" "F.Mask" "F.Paste")
			(net "GND")
		)
		(pad "AA1" smd circle
			(at -8.400034 7.599934)
			(size 0.4064 0.4064)
			(layers "F.Cu" "F.Mask" "F.Paste")
			(net "SSD12_PEX_PWR_EN_R")
		)
		(pad "AA2" smd circle
			(at -7.599934 7.599934)
			(size 0.4064 0.4064)
			(layers "F.Cu" "F.Mask" "F.Paste")
			(net "PRSNT_SSD8_R_N")
		)
		(pad "AA3" smd circle
			(at -6.800088 7.599934)
			(size 0.4064 0.4064)
			(layers "F.Cu" "F.Mask" "F.Paste")
			(net "SSD8_PWRDIS")
		)
		(pad "AA4" smd circle
			(at -5.999988 7.599934)
			(size 0.4064 0.4064)
			(layers "F.Cu" "F.Mask" "F.Paste")
			(net "PWRGD_P12V_SSD9_R")
		)
		(pad "AA5" smd circle
			(at -5.199888 7.599934)
			(size 0.4064 0.4064)
			(layers "F.Cu" "F.Mask" "F.Paste")
			(net "RST_SSD9_PERST_N")
		)
		(pad "AA6" smd circle
			(at -4.400042 7.599934)
			(size 0.4064 0.4064)
			(layers "F.Cu" "F.Mask" "F.Paste")
			(net "PWRGD_P3V3_SSD10_R")
		)
		(pad "AA7" smd circle
			(at -3.599942 7.599934)
			(size 0.4064 0.4064)
			(layers "F.Cu" "F.Mask" "F.Paste")
			(net "SSD10_CLK_EN_N")
		)
		(pad "AA8" smd circle
			(at -2.800096 7.599934)
			(size 0.4064 0.4064)
			(layers "F.Cu" "F.Mask" "F.Paste")
			(net "PRSNT_SSD12_R_N")
		)
		(pad "AA9" smd circle
			(at -1.999996 7.599934)
			(size 0.4064 0.4064)
			(layers "F.Cu" "F.Mask" "F.Paste")
			(net "SSD12_PWRDIS")
		)
		(pad "AA10" smd circle
			(at -1.199896 7.599934)
			(size 0.4064 0.4064)
			(layers "F.Cu" "F.Mask" "F.Paste")
			(net "RST_SSD13_PERST_N")
		)
		(pad "AA11" smd circle
			(at -0.40005 7.599934)
			(size 0.4064 0.4064)
			(layers "F.Cu" "F.Mask" "F.Paste")
			(net "PWRGD_P3V3_SSD14_R")
		)
		(pad "AA12" smd circle
			(at 0.40005 7.599934)
			(size 0.4064 0.4064)
			(layers "F.Cu" "F.Mask" "F.Paste")
			(net "PWRGD_P12V_SSD15_R")
		)
		(pad "AA13" smd circle
			(at 1.199896 7.599934)
			(size 0.4064 0.4064)
			(layers "F.Cu" "F.Mask" "F.Paste")
			(net "RST_SSD15_PERST_N")
		)
		(pad "AA14" smd circle
			(at 1.999996 7.599934)
			(size 0.4064 0.4064)
			(layers "F.Cu" "F.Mask" "F.Paste")
			(net "SSD1_PEX_PWR_EN_R")
		)
		(pad "AA15" smd circle
			(at 2.800096 7.599934)
			(size 0.4064 0.4064)
			(layers "F.Cu" "F.Mask" "F.Paste")
			(net "PRSNT_SSD2_FPGA_N")
		)
		(pad "AA16" smd circle
			(at 3.599942 7.599934)
			(size 0.4064 0.4064)
			(layers "F.Cu" "F.Mask" "F.Paste")
			(net "FPGA_PEX1_MODE_SEL2")
		)
		(pad "AA17" smd circle
			(at 4.400042 7.599934)
			(size 0.4064 0.4064)
			(layers "F.Cu" "F.Mask" "F.Paste")
			(net "SSD3_PWRDIS_BIC_R")
		)
		(pad "AA18" smd circle
			(at 5.199888 7.599934)
			(size 0.4064 0.4064)
			(layers "F.Cu" "F.Mask" "F.Paste")
			(net "RST_PEX_SSD4_PERST_R_N")
		)
		(pad "AA19" smd circle
			(at 5.999988 7.599934)
			(size 0.4064 0.4064)
			(layers "F.Cu" "F.Mask" "F.Paste")
			(net "SSD5_PEX_PWR_EN_R")
		)
		(pad "AA20" smd circle
			(at 6.800088 7.599934)
			(size 0.4064 0.4064)
			(layers "F.Cu" "F.Mask" "F.Paste")
			(net "PRSNT_SSD6_FPGA_N")
		)
		(pad "AA21" smd circle
			(at 7.599934 7.599934)
			(size 0.4064 0.4064)
			(layers "F.Cu" "F.Mask" "F.Paste")
			(net "FPGA_PEX3_MODE_SEL2")
		)
		(pad "AA22" smd circle
			(at 8.400034 7.599934)
			(size 0.4064 0.4064)
			(layers "F.Cu" "F.Mask" "F.Paste")
			(net "PWRGD_PEX2_P1V8_PLL_R")
		)
		(pad "AB1" smd circle
			(at -8.400034 8.400034)
			(size 0.4064 0.4064)
			(layers "F.Cu" "F.Mask" "F.Paste")
			(net "GND")
		)
		(pad "AB2" smd circle
			(at -7.599934 8.400034)
			(size 0.4064 0.4064)
			(layers "F.Cu" "F.Mask" "F.Paste")
			(net "PWRGD_P12V_SSD8_R")
		)
		(pad "AB3" smd circle
			(at -6.800088 8.400034)
			(size 0.4064 0.4064)
			(layers "F.Cu" "F.Mask" "F.Paste")
			(net "RST_SSD8_PERST_N")
		)
		(pad "AB4" smd circle
			(at -5.999988 8.400034)
			(size 0.4064 0.4064)
			(layers "F.Cu" "F.Mask" "F.Paste")
			(net "PWRGD_P3V3_SSD9_R")
		)
		(pad "AB5" smd circle
			(at -5.199888 8.400034)
			(size 0.4064 0.4064)
			(layers "F.Cu" "F.Mask" "F.Paste")
			(net "SSD9_CLK_EN_N")
		)
		(pad "AB6" smd circle
			(at -4.400042 8.400034)
			(size 0.4064 0.4064)
			(layers "F.Cu" "F.Mask" "F.Paste")
			(net "SSD10_PWR_EN")
		)
		(pad "AB7" smd circle
			(at -3.599942 8.400034)
			(size 0.4064 0.4064)
			(layers "F.Cu" "F.Mask" "F.Paste")
			(net "PRSNT_SSD11_R_N")
		)
		(pad "AB8" smd circle
			(at -2.800096 8.400034)
			(size 0.4064 0.4064)
			(layers "F.Cu" "F.Mask" "F.Paste")
			(net "PWRGD_P12V_SSD12_R")
		)
		(pad "AB9" smd circle
			(at -1.999996 8.400034)
			(size 0.4064 0.4064)
			(layers "F.Cu" "F.Mask" "F.Paste")
			(net "RST_SSD12_PERST_N")
		)
		(pad "AB10" smd circle
			(at -1.199896 8.400034)
			(size 0.4064 0.4064)
			(layers "F.Cu" "F.Mask" "F.Paste")
			(net "SSD13_CLK_EN_N")
		)
		(pad "AB11" smd circle
			(at -0.40005 8.400034)
			(size 0.4064 0.4064)
			(layers "F.Cu" "F.Mask" "F.Paste")
			(net "SSD14_PWR_EN")
		)
		(pad "AB12" smd circle
			(at 0.40005 8.400034)
			(size 0.4064 0.4064)
			(layers "F.Cu" "F.Mask" "F.Paste")
			(net "PRSNT_SSD15_R_N")
		)
		(pad "AB13" smd circle
			(at 1.199896 8.400034)
			(size 0.4064 0.4064)
			(layers "F.Cu" "F.Mask" "F.Paste")
			(net "SSD15_PWRDIS")
		)
		(pad "AB14" smd circle
			(at 1.999996 8.400034)
			(size 0.4064 0.4064)
			(layers "F.Cu" "F.Mask" "F.Paste")
			(net "PRSNT_SSD1_FPGA_N")
		)
		(pad "AB15" smd circle
			(at 2.800096 8.400034)
			(size 0.4064 0.4064)
			(layers "F.Cu" "F.Mask" "F.Paste")
			(net "FPGA_PEX0_MODE_SEL1")
		)
		(pad "AB16" smd circle
			(at 3.599942 8.400034)
			(size 0.4064 0.4064)
			(layers "F.Cu" "F.Mask" "F.Paste")
			(net "SSD2_PWRDIS_BIC_R")
		)
		(pad "AB17" smd circle
			(at 4.400042 8.400034)
			(size 0.4064 0.4064)
			(layers "F.Cu" "F.Mask" "F.Paste")
			(net "RST_PEX_SSD3_PERST_R_N")
		)
		(pad "AB18" smd circle
			(at 5.199888 8.400034)
			(size 0.4064 0.4064)
			(layers "F.Cu" "F.Mask" "F.Paste")
			(net "SSD4_PEX_PWR_EN_R")
		)
		(pad "AB19" smd circle
			(at 5.999988 8.400034)
			(size 0.4064 0.4064)
			(layers "F.Cu" "F.Mask" "F.Paste")
			(net "PRSNT_SSD5_FPGA_N")
		)
		(pad "AB20" smd circle
			(at 6.800088 8.400034)
			(size 0.4064 0.4064)
			(layers "F.Cu" "F.Mask" "F.Paste")
			(net "FPGA_PEX2_MODE_SEL1")
		)
		(pad "AB21" smd circle
			(at 7.599934 8.400034)
			(size 0.4064 0.4064)
			(layers "F.Cu" "F.Mask" "F.Paste")
			(net "PU_FPGA_SN")
		)
		(pad "AB22" smd circle
			(at 8.400034 8.400034)
			(size 0.4064 0.4064)
			(layers "F.Cu" "F.Mask" "F.Paste")
			(net "GND")
		)
		(pad "B1" smd circle
			(at -8.400034 -7.599934)
			(size 0.4064 0.4064)
			(layers "F.Cu" "F.Mask" "F.Paste")
			(net "RST_MB_PERST_0_ISO_R_N")
		)
		(pad "B2" smd circle
			(at -7.599934 -7.599934)
			(size 0.4064 0.4064)
			(layers "F.Cu" "F.Mask" "F.Paste")
			(net "MB_SWB_PWRGD")
		)
		(pad "B3" smd circle
			(at -6.800088 -7.599934)
			(size 0.4064 0.4064)
			(layers "F.Cu" "F.Mask" "F.Paste")
			(net "PRSNT_GPU_ISO_R1_N")
		)
		(pad "B4" smd circle
			(at -5.999988 -7.599934)
			(size 0.4064 0.4064)
			(layers "F.Cu" "F.Mask" "F.Paste")
			(net "SSD2_PWR_EN")
		)
		(pad "B5" smd circle
			(at -5.199888 -7.599934)
			(size 0.4064 0.4064)
			(layers "F.Cu" "F.Mask" "F.Paste")
			(net "SYS_PWR_READY_N")
		)
		(pad "B6" smd circle
			(at -4.400042 -7.599934)
			(size 0.4064 0.4064)
			(layers "F.Cu" "F.Mask" "F.Paste")
			(net "FPGA_HEARTBEAT_N")
		)
		(pad "B7" smd circle
			(at -3.599942 -7.599934)
			(size 0.4064 0.4064)
			(layers "F.Cu" "F.Mask" "F.Paste")
			(net "GND")
		)
		(pad "B8" smd circle
			(at -2.800096 -7.599934)
			(size 0.4064 0.4064)
			(layers "F.Cu" "F.Mask" "F.Paste")
			(net "SMB_PEX2_FPGA_SCL")
		)
		(pad "B9" smd circle
			(at -1.999996 -7.599934)
			(size 0.4064 0.4064)
			(layers "F.Cu" "F.Mask" "F.Paste")
			(net "PRSNT_SSD0_R_N")
		)
		(pad "B10" smd circle
			(at -1.199896 -7.599934)
			(size 0.4064 0.4064)
			(layers "F.Cu" "F.Mask" "F.Paste")
			(net "SSD0_CLK_EN_N")
		)
		(pad "B11" smd circle
			(at -0.40005 -7.599934)
			(size 0.4064 0.4064)
			(layers "F.Cu" "F.Mask" "F.Paste")
			(net "SSD1_PWR_EN")
		)
		(pad "B12" smd circle
			(at 0.40005 -7.599934)
			(size 0.4064 0.4064)
			(layers "F.Cu" "F.Mask" "F.Paste")
			(net "SMB_BIC_FPGA_R_SCL")
		)
		(pad "B13" smd circle
			(at 1.199896 -7.599934)
			(size 0.4064 0.4064)
			(layers "F.Cu" "F.Mask" "F.Paste")
			(net "PWRGD_P3V3_SSD3_R")
		)
		(pad "B14" smd circle
			(at 1.999996 -7.599934)
			(size 0.4064 0.4064)
			(layers "F.Cu" "F.Mask" "F.Paste")
			(net "SSD3_CLK_EN_N")
		)
		(pad "B15" smd circle
			(at 2.800096 -7.599934)
			(size 0.4064 0.4064)
			(layers "F.Cu" "F.Mask" "F.Paste")
			(net "RST_SSD4_PERST_N")
		)
		(pad "B16" smd circle
			(at 3.599942 -7.599934)
			(size 0.4064 0.4064)
			(layers "F.Cu" "F.Mask" "F.Paste")
			(net "GND")
		)
		(pad "B17" smd circle
			(at 4.400042 -7.599934)
			(size 0.4064 0.4064)
			(layers "F.Cu" "F.Mask" "F.Paste")
			(net "PWRGD_P3V3_SSD5_R")
		)
		(pad "B18" smd circle
			(at 5.199888 -7.599934)
			(size 0.4064 0.4064)
			(layers "F.Cu" "F.Mask" "F.Paste")
			(net "SSD5_CLK_EN_N")
		)
		(pad "B19" smd circle
			(at 5.999988 -7.599934)
			(size 0.4064 0.4064)
			(layers "F.Cu" "F.Mask" "F.Paste")
			(net "SSD6_PWR_EN")
		)
		(pad "B20" smd circle
			(at 6.800088 -7.599934)
			(size 0.4064 0.4064)
			(layers "F.Cu" "F.Mask" "F.Paste")
			(net "PRSNT_SSD7_R_N")
		)
		(pad "B21" smd circle
			(at 7.599934 -7.599934)
			(size 0.4064 0.4064)
			(layers "F.Cu" "F.Mask" "F.Paste")
			(net "SSD7_PWRDIS")
		)
		(pad "B22" smd circle
			(at 8.400034 -7.599934)
			(size 0.4064 0.4064)
			(layers "F.Cu" "F.Mask" "F.Paste")
			(net "Net_8564")
		)
		(pad "C1" smd circle
			(at -8.400034 -6.800088)
			(size 0.4064 0.4064)
			(layers "F.Cu" "F.Mask" "F.Paste")
			(net "PWRGD_P0V8_PEX3_R")
		)
		(pad "C2" smd circle
			(at -7.599934 -6.800088)
			(size 0.4064 0.4064)
			(layers "F.Cu" "F.Mask" "F.Paste")
			(net "GND")
		)
		(pad "C3" smd circle
			(at -6.800088 -6.800088)
			(size 0.4064 0.4064)
			(layers "F.Cu" "F.Mask" "F.Paste")
			(net "RST_GPU_PERST_1_N")
		)
		(pad "C4" smd circle
			(at -5.999988 -6.800088)
			(size 0.4064 0.4064)
			(layers "F.Cu" "F.Mask" "F.Paste")
			(net "RST_GPU_PERST_2_N")
		)
		(pad "C5" smd circle
			(at -5.199888 -6.800088)
			(size 0.4064 0.4064)
			(layers "F.Cu" "F.Mask" "F.Paste")
			(net "SSD2_CLK_EN_N")
		)
		(pad "C6" smd circle
			(at -4.400042 -6.800088)
			(size 0.4064 0.4064)
			(layers "F.Cu" "F.Mask" "F.Paste")
			(net "SMB_PEX0_FPGA_SCL")
		)
		(pad "C7" smd circle
			(at -3.599942 -6.800088)
			(size 0.4064 0.4064)
			(layers "F.Cu" "F.Mask" "F.Paste")
			(net "P3V3_FPGA_VCCIO0")
		)
		(pad "C8" smd circle
			(at -2.800096 -6.800088)
			(size 0.4064 0.4064)
			(layers "F.Cu" "F.Mask" "F.Paste")
			(net "SMB_PEX1_FPGA_SCL")
		)
		(pad "C9" smd circle
			(at -1.999996 -6.800088)
			(size 0.4064 0.4064)
			(layers "F.Cu" "F.Mask" "F.Paste")
			(net "SMB_PEX3_FPGA_SCL")
		)
		(pad "C10" smd circle
			(at -1.199896 -6.800088)
			(size 0.4064 0.4064)
			(layers "F.Cu" "F.Mask" "F.Paste")
			(net "JTAG_FPGA_TMS")
		)
		(pad "C11" smd circle
			(at -0.40005 -6.800088)
			(size 0.4064 0.4064)
			(layers "F.Cu" "F.Mask" "F.Paste")
			(net "GND")
		)
		(pad "C12" smd circle
			(at 0.40005 -6.800088)
			(size 0.4064 0.4064)
			(layers "F.Cu" "F.Mask" "F.Paste")
			(net "P3V3_FPGA_VCCIO0")
		)
		(pad "C13" smd circle
			(at 1.199896 -6.800088)
			(size 0.4064 0.4064)
			(layers "F.Cu" "F.Mask" "F.Paste")
			(net "SSD3_PWR_EN")
		)
		(pad "C14" smd circle
			(at 1.999996 -6.800088)
			(size 0.4064 0.4064)
			(layers "F.Cu" "F.Mask" "F.Paste")
			(net "PRSNT_SSD4_R_N")
		)
		(pad "C15" smd circle
			(at 2.800096 -6.800088)
			(size 0.4064 0.4064)
			(layers "F.Cu" "F.Mask" "F.Paste")
			(net "SSD4_CLK_EN_N")
		)
		(pad "C16" smd circle
			(at 3.599942 -6.800088)
			(size 0.4064 0.4064)
			(layers "F.Cu" "F.Mask" "F.Paste")
			(net "P3V3_FPGA_VCCIO0")
		)
		(pad "C17" smd circle
			(at 4.400042 -6.800088)
			(size 0.4064 0.4064)
			(layers "F.Cu" "F.Mask" "F.Paste")
			(net "SSD5_PWR_EN")
		)
		(pad "C18" smd circle
			(at 5.199888 -6.800088)
			(size 0.4064 0.4064)
			(layers "F.Cu" "F.Mask" "F.Paste")
			(net "SSD6_PWRDIS")
		)
		(pad "C19" smd circle
			(at 5.999988 -6.800088)
			(size 0.4064 0.4064)
			(layers "F.Cu" "F.Mask" "F.Paste")
			(net "RST_SSD7_PERST_N")
		)
		(pad "C20" smd circle
			(at 6.800088 -6.800088)
			(size 0.4064 0.4064)
			(layers "F.Cu" "F.Mask" "F.Paste")
			(net "SSD7_CLK_EN_N")
		)
		(pad "C21" smd circle
			(at 7.599934 -6.800088)
			(size 0.4064 0.4064)
			(layers "F.Cu" "F.Mask" "F.Paste")
			(net "PRSNT_NIC0_R_N")
		)
		(pad "C22" smd circle
			(at 8.400034 -6.800088)
			(size 0.4064 0.4064)
			(layers "F.Cu" "F.Mask" "F.Paste")
			(net "PWRGD_P12V_NIC0_R")
		)
	)
)
